(kicad_pcb
	(version 20260206)
	(generator "pcbnew")
	(generator_version "10.0")
	(general
		(thickness 1.6)
		(legacy_teardrops no)
	)
	(paper "A4")
	(title_block
		(title "v1-chassis-manager — T6M_CM_d_v01_1031_1645.brd")
		(comment 1 "Open CloudServer (Microsoft) / footprints 795-796 of 2512")
	)
	(layers
		(0 "F.Cu" signal "TOP")
		(4 "In1.Cu" signal "GND1")
		(6 "In2.Cu" signal "IN1")
		(8 "In3.Cu" signal "VCC1")
		(10 "In4.Cu" signal "VCC2")
		(12 "In5.Cu" signal "GND2")
		(14 "In6.Cu" signal "IN2")
		(16 "In7.Cu" signal "IN3")
		(18 "In8.Cu" signal "GND3")
		(2 "B.Cu" signal "BOTTOM")
		(9 "F.Adhes" user "F.Adhesive")
		(11 "B.Adhes" user "B.Adhesive")
		(13 "F.Paste" user "Package Geometry/Pastemask Top")
		(15 "B.Paste" user "Package Geometry/Pastemask Bottom")
		(5 "F.SilkS" user "Ref Des/Silkscreen Top")
		(7 "B.SilkS" user "Ref Des/Silkscreen Bottom")
		(1 "F.Mask" user "Board Geometry/Soldermask Top")
		(3 "B.Mask" user "Board Geometry/Soldermask Bottom")
		(17 "Dwgs.User" user "User.Drawings")
		(19 "Cmts.User" user "User.Comments")
		(21 "Eco1.User" user "User.Eco1")
		(23 "Eco2.User" user "User.Eco2")
		(25 "Edge.Cuts" user "Board Geometry/Outline")
		(27 "Margin" user)
		(31 "F.CrtYd" user "Package Geometry/Place Bound Top")
		(29 "B.CrtYd" user "Package Geometry/Place Bound Bottom")
		(35 "F.Fab" user "Ref Des/Assembly Top")
		(33 "B.Fab" user "Ref Des/Assembly Bottom")
	)
	(footprint ""
		(layer "F.Cu")
		(at 109.979968 -149.245066)
		(property "Reference" "R1004"
			(at 2.195068 0.337566 0)
			(unlocked yes)
			(layer "F.SilkS")
			(effects
				(font
					(size 0.635 0.4064)
					(thickness 0.1524)
				)
				(justify left)
			)
		)
		(property "Value" ""
			(at 0 0 0)
			(layer "F.Fab")
			(effects
				(font
					(size 1.27 1.27)
				)
			)
		)
		(duplicate_pad_numbers_are_jumpers no)
		(fp_line
			(start -0.7874 -0.4064)
			(end 0.7874 -0.4064)
			(stroke
				(width 0.1524)
				(type default)
			)
			(layer "F.SilkS")
		)
		(fp_line
			(start -0.7874 0.4064)
			(end -0.7874 -0.4064)
			(stroke
				(width 0.1524)
				(type default)
			)
			(layer "F.SilkS")
		)
		(fp_line
			(start 0.7874 -0.4064)
			(end 0.7874 0.4064)
			(stroke
				(width 0.1524)
				(type default)
			)
			(layer "F.SilkS")
		)
		(fp_line
			(start 0.7874 0.4064)
			(end -0.7874 0.4064)
			(stroke
				(width 0.1524)
				(type default)
			)
			(layer "F.SilkS")
		)
		(fp_poly
			(pts
				(xy -0.508 0.2794) (xy -0.508 0.2286) (xy -0.635 0.2286) (xy -0.635 -0.254) (xy -0.5334 -0.254)
				(xy -0.5334 -0.2794) (xy 0.5334 -0.2794) (xy 0.5334 -0.254) (xy 0.635 -0.254) (xy 0.635 0.254) (xy 0.5334 0.254)
				(xy 0.5334 0.2794)
			)
			(stroke
				(width 0)
				(type default)
			)
			(fill no)
			(layer "F.CrtYd")
		)
		(pad "1" smd rect
			(at 0.40005 0)
			(size 0.4572 0.508)
			(layers "F.Cu" "F.Mask" "F.Paste")
			(net "GND")
		)
		(pad "2" smd rect
			(at -0.40005 0)
			(size 0.4572 0.508)
			(layers "F.Cu" "F.Mask" "F.Paste")
			(net "POWER_SW2_PWR_CTR_12V")
		)
	)
	(footprint ""
		(layer "F.Cu")
		(at 84.171282 -4.70662 180)
		(property "Reference" "PC49"
			(at -2.299462 -2.666746 0)
			(unlocked yes)
			(layer "F.SilkS")
			(effects
				(font
					(size 0.7874 0.5842)
					(thickness 0.1524)
				)
				(justify left)
			)
		)
		(property "Value" ""
			(at 0 0 180)
			(layer "F.Fab")
			(effects
				(font
					(size 1.27 1.27)
				)
			)
		)
		(duplicate_pad_numbers_are_jumpers no)
		(fp_line
			(start 1.905 0.8636)
			(end -1.905 0.8636)
			(stroke
				(width 0.1524)
				(type default)
			)
			(layer "F.SilkS")
		)
		(fp_line
			(start 1.905 -0.8636)
			(end 1.905 0.8636)
			(stroke
				(width 0.1524)
				(type default)
			)
			(layer "F.SilkS")
		)
		(fp_line
			(start 0 0.8382)
			(end 0 -0.8382)
			(stroke
				(width 0.1524)
				(type default)
			)
			(layer "F.SilkS")
		)
		(fp_line
			(start -1.905 0.8636)
			(end -1.905 -0.8636)
			(stroke
				(width 0.1524)
				(type default)
			)
			(layer "F.SilkS")
		)
		(fp_line
			(start -1.905 -0.8636)
			(end 1.905 -0.8636)
			(stroke
				(width 0.1524)
				(type default)
			)
			(layer "F.SilkS")
		)
		(fp_rect
			(start -1.524 0.7366)
			(end 1.524 -0.7366)
			(stroke
				(width 0)
				(type default)
			)
			(fill no)
			(layer "F.CrtYd")
		)
		(pad "1" smd rect
			(at 0.94996 0 180)
			(size 1.1176 1.3716)
			(layers "F.Cu" "F.Mask" "F.Paste")
			(net "P3V3_NODE1")
		)
		(pad "2" smd rect
			(at -0.94996 0 180)
			(size 1.1176 1.3716)
			(layers "F.Cu" "F.Mask" "F.Paste")
			(net "GND")
		)
	)
)
